(kicad_pcb
	(version 20260206)
	(generator "pcbnew")
	(generator_version "10.0")
	(general
		(thickness 1.6)
		(legacy_teardrops no)
	)
	(paper "A4")
	(title_block
		(title "03242023_DA0F0TMBIJ0_F0T_Motherboard_J_brd_V01_OCP.brd")
		(comment 1 "Grand Teton / footprints 3372-3377 of 6105")
	)
	(layers
		(0 "F.Cu" signal "TOP")
		(4 "In1.Cu" signal "GND")
		(6 "In2.Cu" signal "IN1")
		(8 "In3.Cu" signal "GND1")
		(10 "In4.Cu" signal "IN2")
		(12 "In5.Cu" signal "GND2")
		(14 "In6.Cu" signal "IN3")
		(16 "In7.Cu" signal "GND3")
		(18 "In8.Cu" signal "VCC")
		(20 "In9.Cu" signal "VCC1")
		(22 "In10.Cu" signal "GND4")
		(24 "In11.Cu" signal "IN4")
		(26 "In12.Cu" signal "GND5")
		(28 "In13.Cu" signal "IN5")
		(30 "In14.Cu" signal "GND6")
		(32 "In15.Cu" signal "IN6")
		(34 "In16.Cu" signal "GND7")
		(2 "B.Cu" signal "BOTTOM")
		(9 "F.Adhes" user "F.Adhesive")
		(11 "B.Adhes" user "B.Adhesive")
		(13 "F.Paste" user "Package Geometry/Pastemask Top")
		(15 "B.Paste" user "Package Geometry/Pastemask Bottom")
		(5 "F.SilkS" user "Ref Des/Silkscreen Top")
		(7 "B.SilkS" user "Ref Des/Silkscreen Bottom")
		(1 "F.Mask" user "Board Geometry/Soldermask Top")
		(3 "B.Mask" user "Board Geometry/Soldermask Bottom")
		(17 "Dwgs.User" user "User.Drawings")
		(19 "Cmts.User" user "User.Comments")
		(21 "Eco1.User" user "User.Eco1")
		(23 "Eco2.User" user "User.Eco2")
		(25 "Edge.Cuts" user "Board Geometry/Outline")
		(27 "Margin" user)
		(31 "F.CrtYd" user "Package Geometry/Place Bound Top")
		(29 "B.CrtYd" user "Package Geometry/Place Bound Bottom")
		(35 "F.Fab" user "Ref Des/Assembly Top")
		(33 "B.Fab" user "Ref Des/Assembly Bottom")
	)
	(footprint ""
		(layer "F.Cu")
		(at 115.951 -54.193948 180)
		(property "Reference" "R4632"
			(at 0 0 180)
			(layer "F.SilkS")
			(hide yes)
			(effects
				(font
					(size 1.27 1.27)
				)
			)
		)
		(property "Value" ""
			(at 0 0 180)
			(layer "F.Fab")
			(effects
				(font
					(size 1.27 1.27)
				)
			)
		)
		(duplicate_pad_numbers_are_jumpers no)
		(fp_line
			(start 0.7874 0.4064)
			(end -0.7874 0.4064)
			(stroke
				(width 0.1524)
				(type default)
			)
			(layer "F.SilkS")
		)
		(fp_line
			(start 0.7874 -0.4064)
			(end 0.7874 0.4064)
			(stroke
				(width 0.1524)
				(type default)
			)
			(layer "F.SilkS")
		)
		(fp_line
			(start -0.7874 0.4064)
			(end -0.7874 -0.4064)
			(stroke
				(width 0.1524)
				(type default)
			)
			(layer "F.SilkS")
		)
		(fp_line
			(start -0.7874 -0.4064)
			(end 0.7874 -0.4064)
			(stroke
				(width 0.1524)
				(type default)
			)
			(layer "F.SilkS")
		)
		(fp_line
			(start 0.67945 0.3048)
			(end 0.120396 0.3048)
			(stroke
				(width 0.1)
				(type default)
			)
			(layer "F.Fab")
		)
		(fp_line
			(start 0.67945 -0.3048)
			(end 0.67945 0.3048)
			(stroke
				(width 0.1)
				(type default)
			)
			(layer "F.Fab")
		)
		(fp_line
			(start 0.12065 -0.2794)
			(end 0.12065 -0.3048)
			(stroke
				(width 0.1)
				(type default)
			)
			(layer "F.Fab")
		)
		(fp_line
			(start 0.12065 -0.3048)
			(end 0.67945 -0.3048)
			(stroke
				(width 0.1)
				(type default)
			)
			(layer "F.Fab")
		)
		(fp_line
			(start 0.120396 0.3048)
			(end 0.120396 0.2794)
			(stroke
				(width 0.1)
				(type default)
			)
			(layer "F.Fab")
		)
		(fp_line
			(start 0.120396 0.2794)
			(end -0.12065 0.2794)
			(stroke
				(width 0.1)
				(type default)
			)
			(layer "F.Fab")
		)
		(fp_line
			(start -0.12065 0.3048)
			(end -0.67945 0.3048)
			(stroke
				(width 0.1)
				(type default)
			)
			(layer "F.Fab")
		)
		(fp_line
			(start -0.12065 0.2794)
			(end -0.12065 0.3048)
			(stroke
				(width 0.1)
				(type default)
			)
			(layer "F.Fab")
		)
		(fp_line
			(start -0.12065 -0.2794)
			(end 0.12065 -0.2794)
			(stroke
				(width 0.1)
				(type default)
			)
			(layer "F.Fab")
		)
		(fp_line
			(start -0.12065 -0.305054)
			(end -0.12065 -0.2794)
			(stroke
				(width 0.1)
				(type default)
			)
			(layer "F.Fab")
		)
		(fp_line
			(start -0.67945 0.3048)
			(end -0.67945 -0.305054)
			(stroke
				(width 0.1)
				(type default)
			)
			(layer "F.Fab")
		)
		(fp_line
			(start -0.67945 -0.305054)
			(end -0.12065 -0.305054)
			(stroke
				(width 0.1)
				(type default)
			)
			(layer "F.Fab")
		)
		(pad "1" smd circle
			(at -0.40005 0 180)
			(size 0 0)
			(layers "F.Cu" "F.Mask" "F.Paste")
			(net "JTAG_BMC_SW_TMS_R")
		)
		(pad "2" smd circle
			(at 0.40005 0 180)
			(size 0 0)
			(layers "F.Cu" "F.Mask" "F.Paste")
			(net "JTAG_BMC_SW_TMS")
		)
	)
	(footprint ""
		(layer "F.Cu")
		(at 96.138238 -414.75533 -90)
		(property "Reference" "R4187"
			(at 0 0 270)
			(layer "F.SilkS")
			(hide yes)
			(effects
				(font
					(size 1.27 1.27)
				)
			)
		)
		(property "Value" ""
			(at 0 0 270)
			(layer "F.Fab")
			(effects
				(font
					(size 1.27 1.27)
				)
			)
		)
		(duplicate_pad_numbers_are_jumpers no)
		(fp_line
			(start -0.7874 0.4064)
			(end -0.7874 -0.4064)
			(stroke
				(width 0.1524)
				(type default)
			)
			(layer "F.SilkS")
		)
		(fp_line
			(start 0.7874 0.4064)
			(end -0.7874 0.4064)
			(stroke
				(width 0.1524)
				(type default)
			)
			(layer "F.SilkS")
		)
		(fp_line
			(start -0.7874 -0.4064)
			(end 0.7874 -0.4064)
			(stroke
				(width 0.1524)
				(type default)
			)
			(layer "F.SilkS")
		)
		(fp_line
			(start 0.7874 -0.4064)
			(end 0.7874 0.4064)
			(stroke
				(width 0.1524)
				(type default)
			)
			(layer "F.SilkS")
		)
		(fp_line
			(start -0.67945 0.3048)
			(end -0.67945 -0.305054)
			(stroke
				(width 0.1)
				(type default)
			)
			(layer "F.Fab")
		)
		(fp_line
			(start -0.12065 0.3048)
			(end -0.67945 0.3048)
			(stroke
				(width 0.1)
				(type default)
			)
			(layer "F.Fab")
		)
		(fp_line
			(start 0.120396 0.3048)
			(end 0.120396 0.2794)
			(stroke
				(width 0.1)
				(type default)
			)
			(layer "F.Fab")
		)
		(fp_line
			(start 0.67945 0.3048)
			(end 0.120396 0.3048)
			(stroke
				(width 0.1)
				(type default)
			)
			(layer "F.Fab")
		)
		(fp_line
			(start -0.12065 0.2794)
			(end -0.12065 0.3048)
			(stroke
				(width 0.1)
				(type default)
			)
			(layer "F.Fab")
		)
		(fp_line
			(start 0.120396 0.2794)
			(end -0.12065 0.2794)
			(stroke
				(width 0.1)
				(type default)
			)
			(layer "F.Fab")
		)
		(fp_line
			(start -0.12065 -0.2794)
			(end 0.12065 -0.2794)
			(stroke
				(width 0.1)
				(type default)
			)
			(layer "F.Fab")
		)
		(fp_line
			(start 0.12065 -0.2794)
			(end 0.12065 -0.3048)
			(stroke
				(width 0.1)
				(type default)
			)
			(layer "F.Fab")
		)
		(fp_line
			(start 0.12065 -0.3048)
			(end 0.67945 -0.3048)
			(stroke
				(width 0.1)
				(type default)
			)
			(layer "F.Fab")
		)
		(fp_line
			(start 0.67945 -0.3048)
			(end 0.67945 0.3048)
			(stroke
				(width 0.1)
				(type default)
			)
			(layer "F.Fab")
		)
		(fp_line
			(start -0.67945 -0.305054)
			(end -0.12065 -0.305054)
			(stroke
				(width 0.1)
				(type default)
			)
			(layer "F.Fab")
		)
		(fp_line
			(start -0.12065 -0.305054)
			(end -0.12065 -0.2794)
			(stroke
				(width 0.1)
				(type default)
			)
			(layer "F.Fab")
		)
		(pad "1" smd circle
			(at -0.40005 0 270)
			(size 0 0)
			(layers "F.Cu" "F.Mask" "F.Paste")
			(net "U272_2_ADD2")
		)
		(pad "2" smd circle
			(at 0.40005 0 270)
			(size 0 0)
			(layers "F.Cu" "F.Mask" "F.Paste")
			(net "GND")
		)
	)
	(footprint ""
		(layer "F.Cu")
		(at 277.230078 -417.2839 90)
		(property "Reference" "R4672"
			(at 0 0 90)
			(layer "F.SilkS")
			(hide yes)
			(effects
				(font
					(size 1.27 1.27)
				)
			)
		)
		(property "Value" ""
			(at 0 0 90)
			(layer "F.Fab")
			(effects
				(font
					(size 1.27 1.27)
				)
			)
		)
		(duplicate_pad_numbers_are_jumpers no)
		(fp_line
			(start 0.7874 -0.4064)
			(end 0.7874 0.4064)
			(stroke
				(width 0.1524)
				(type default)
			)
			(layer "F.SilkS")
		)
		(fp_line
			(start -0.7874 -0.4064)
			(end 0.7874 -0.4064)
			(stroke
				(width 0.1524)
				(type default)
			)
			(layer "F.SilkS")
		)
		(fp_line
			(start 0.7874 0.4064)
			(end -0.7874 0.4064)
			(stroke
				(width 0.1524)
				(type default)
			)
			(layer "F.SilkS")
		)
		(fp_line
			(start -0.7874 0.4064)
			(end -0.7874 -0.4064)
			(stroke
				(width 0.1524)
				(type default)
			)
			(layer "F.SilkS")
		)
		(fp_line
			(start -0.12065 -0.305054)
			(end -0.12065 -0.2794)
			(stroke
				(width 0.1)
				(type default)
			)
			(layer "F.Fab")
		)
		(fp_line
			(start -0.67945 -0.305054)
			(end -0.12065 -0.305054)
			(stroke
				(width 0.1)
				(type default)
			)
			(layer "F.Fab")
		)
		(fp_line
			(start 0.67945 -0.3048)
			(end 0.67945 0.3048)
			(stroke
				(width 0.1)
				(type default)
			)
			(layer "F.Fab")
		)
		(fp_line
			(start 0.12065 -0.3048)
			(end 0.67945 -0.3048)
			(stroke
				(width 0.1)
				(type default)
			)
			(layer "F.Fab")
		)
		(fp_line
			(start 0.12065 -0.2794)
			(end 0.12065 -0.3048)
			(stroke
				(width 0.1)
				(type default)
			)
			(layer "F.Fab")
		)
		(fp_line
			(start -0.12065 -0.2794)
			(end 0.12065 -0.2794)
			(stroke
				(width 0.1)
				(type default)
			)
			(layer "F.Fab")
		)
		(fp_line
			(start 0.120396 0.2794)
			(end -0.12065 0.2794)
			(stroke
				(width 0.1)
				(type default)
			)
			(layer "F.Fab")
		)
		(fp_line
			(start -0.12065 0.2794)
			(end -0.12065 0.3048)
			(stroke
				(width 0.1)
				(type default)
			)
			(layer "F.Fab")
		)
		(fp_line
			(start 0.67945 0.3048)
			(end 0.120396 0.3048)
			(stroke
				(width 0.1)
				(type default)
			)
			(layer "F.Fab")
		)
		(fp_line
			(start 0.120396 0.3048)
			(end 0.120396 0.2794)
			(stroke
				(width 0.1)
				(type default)
			)
			(layer "F.Fab")
		)
		(fp_line
			(start -0.12065 0.3048)
			(end -0.67945 0.3048)
			(stroke
				(width 0.1)
				(type default)
			)
			(layer "F.Fab")
		)
		(fp_line
			(start -0.67945 0.3048)
			(end -0.67945 -0.305054)
			(stroke
				(width 0.1)
				(type default)
			)
			(layer "F.Fab")
		)
		(pad "1" smd circle
			(at -0.40005 0 90)
			(size 0 0)
			(layers "F.Cu" "F.Mask" "F.Paste")
			(net "P3V3_AUX")
		)
		(pad "2" smd circle
			(at 0.40005 0 90)
			(size 0 0)
			(layers "F.Cu" "F.Mask" "F.Paste")
			(net "A_HSC_LOW_GATE")
		)
	)
	(footprint ""
		(layer "F.Cu")
		(at 288.794952 -354.000816 -90)
		(property "Reference" "PL210"
			(at -2.553462 8.124952 0)
			(unlocked yes)
			(layer "F.SilkS")
			(effects
				(font
					(size 0.7874 0.5842)
					(thickness 0.1524)
				)
				(justify left)
			)
		)
		(property "Value" ""
			(at 0 0 270)
			(layer "F.Fab")
			(effects
				(font
					(size 1.27 1.27)
				)
			)
		)
		(duplicate_pad_numbers_are_jumpers no)
		(fp_line
			(start -4.99999 3.750056)
			(end -4.99999 2.2479)
			(stroke
				(width 0.1524)
				(type default)
			)
			(layer "F.SilkS")
		)
		(fp_line
			(start 0 3.750056)
			(end -4.99999 3.750056)
			(stroke
				(width 0.1524)
				(type default)
			)
			(layer "F.SilkS")
		)
		(fp_line
			(start 4.99999 3.750056)
			(end 0 3.750056)
			(stroke
				(width 0.1524)
				(type default)
			)
			(layer "F.SilkS")
		)
		(fp_line
			(start 4.99999 2.2352)
			(end 4.99999 3.750056)
			(stroke
				(width 0.1524)
				(type default)
			)
			(layer "F.SilkS")
		)
		(fp_line
			(start -4.99999 -2.2479)
			(end -4.99999 -3.750056)
			(stroke
				(width 0.1524)
				(type default)
			)
			(layer "F.SilkS")
		)
		(fp_line
			(start -4.99999 -3.750056)
			(end 4.99999 -3.750056)
			(stroke
				(width 0.1524)
				(type default)
			)
			(layer "F.SilkS")
		)
		(fp_line
			(start 4.99999 -3.750056)
			(end 4.99999 -2.2479)
			(stroke
				(width 0.1524)
				(type default)
			)
			(layer "F.SilkS")
		)
		(fp_line
			(start -4.99999 3.750056)
			(end -4.99999 -3.750056)
			(stroke
				(width 0.1)
				(type default)
			)
			(layer "F.Fab")
		)
		(fp_line
			(start 0 3.750056)
			(end -4.99999 3.750056)
			(stroke
				(width 0.1)
				(type default)
			)
			(layer "F.Fab")
		)
		(fp_line
			(start 4.99999 3.750056)
			(end 0 3.750056)
			(stroke
				(width 0.1)
				(type default)
			)
			(layer "F.Fab")
		)
		(fp_line
			(start -4.99999 -3.750056)
			(end 4.99999 -3.750056)
			(stroke
				(width 0.1)
				(type default)
			)
			(layer "F.Fab")
		)
		(fp_line
			(start 4.99999 -3.750056)
			(end 4.99999 3.750056)
			(stroke
				(width 0.1)
				(type default)
			)
			(layer "F.Fab")
		)
		(pad "1" smd rect
			(at -3.299968 0 270)
			(size 3.302 4.2164)
			(layers "F.Cu" "F.Mask" "F.Paste")
			(net "SW_PVCCFA_EHV_FIVRA_CPU0_SW4")
		)
		(pad "2" smd rect
			(at 3.299968 0 270)
			(size 3.302 4.2164)
			(layers "F.Cu" "F.Mask" "F.Paste")
			(net "PVCCFA_EHV_FIVRA_CPU0")
		)
	)
	(footprint ""
		(layer "F.Cu")
		(at 298.04995 -417.2204)
		(property "Reference" "R4576"
			(at 0 0 0)
			(layer "F.SilkS")
			(hide yes)
			(effects
				(font
					(size 1.27 1.27)
				)
			)
		)
		(property "Value" ""
			(at 0 0 0)
			(layer "F.Fab")
			(effects
				(font
					(size 1.27 1.27)
				)
			)
		)
		(duplicate_pad_numbers_are_jumpers no)
		(fp_line
			(start -0.7874 -0.4064)
			(end 0.7874 -0.4064)
			(stroke
				(width 0.1524)
				(type default)
			)
			(layer "F.SilkS")
		)
		(fp_line
			(start -0.7874 0.4064)
			(end -0.7874 -0.4064)
			(stroke
				(width 0.1524)
				(type default)
			)
			(layer "F.SilkS")
		)
		(fp_line
			(start 0.7874 -0.4064)
			(end 0.7874 0.4064)
			(stroke
				(width 0.1524)
				(type default)
			)
			(layer "F.SilkS")
		)
		(fp_line
			(start 0.7874 0.4064)
			(end -0.7874 0.4064)
			(stroke
				(width 0.1524)
				(type default)
			)
			(layer "F.SilkS")
		)
		(fp_line
			(start -0.67945 -0.305054)
			(end -0.12065 -0.305054)
			(stroke
				(width 0.1)
				(type default)
			)
			(layer "F.Fab")
		)
		(fp_line
			(start -0.67945 0.3048)
			(end -0.67945 -0.305054)
			(stroke
				(width 0.1)
				(type default)
			)
			(layer "F.Fab")
		)
		(fp_line
			(start -0.12065 -0.305054)
			(end -0.12065 -0.2794)
			(stroke
				(width 0.1)
				(type default)
			)
			(layer "F.Fab")
		)
		(fp_line
			(start -0.12065 -0.2794)
			(end 0.12065 -0.2794)
			(stroke
				(width 0.1)
				(type default)
			)
			(layer "F.Fab")
		)
		(fp_line
			(start -0.12065 0.2794)
			(end -0.12065 0.3048)
			(stroke
				(width 0.1)
				(type default)
			)
			(layer "F.Fab")
		)
		(fp_line
			(start -0.12065 0.3048)
			(end -0.67945 0.3048)
			(stroke
				(width 0.1)
				(type default)
			)
			(layer "F.Fab")
		)
		(fp_line
			(start 0.120396 0.2794)
			(end -0.12065 0.2794)
			(stroke
				(width 0.1)
				(type default)
			)
			(layer "F.Fab")
		)
		(fp_line
			(start 0.120396 0.3048)
			(end 0.120396 0.2794)
			(stroke
				(width 0.1)
				(type default)
			)
			(layer "F.Fab")
		)
		(fp_line
			(start 0.12065 -0.3048)
			(end 0.67945 -0.3048)
			(stroke
				(width 0.1)
				(type default)
			)
			(layer "F.Fab")
		)
		(fp_line
			(start 0.12065 -0.2794)
			(end 0.12065 -0.3048)
			(stroke
				(width 0.1)
				(type default)
			)
			(layer "F.Fab")
		)
		(fp_line
			(start 0.67945 -0.3048)
			(end 0.67945 0.3048)
			(stroke
				(width 0.1)
				(type default)
			)
			(layer "F.Fab")
		)
		(fp_line
			(start 0.67945 0.3048)
			(end 0.120396 0.3048)
			(stroke
				(width 0.1)
				(type default)
			)
			(layer "F.Fab")
		)
		(pad "1" smd circle
			(at -0.40005 0)
			(size 0 0)
			(layers "F.Cu" "F.Mask" "F.Paste")
			(net "GPU_3V3IO_RSVD5_FFU")
		)
		(pad "2" smd circle
			(at 0.40005 0)
			(size 0 0)
			(layers "F.Cu" "F.Mask" "F.Paste")
			(net "GPU_3V3IO_RSVD5_FFU_ISO")
		)
	)
	(footprint ""
		(layer "F.Cu")
		(at 328.620882 -333.61884)
		(property "Reference" "PL8"
			(at -6.299962 4.735322 0)
			(unlocked yes)
			(layer "F.SilkS")
			(effects
				(font
					(size 0.7874 0.5842)
					(thickness 0.1524)
				)
				(justify left)
			)
		)
		(property "Value" ""
			(at 0 0 0)
			(layer "F.Fab")
			(effects
				(font
					(size 1.27 1.27)
				)
			)
		)
		(duplicate_pad_numbers_are_jumpers no)
		(fp_line
			(start -3.750056 -5.500116)
			(end -2.393442 -5.500116)
			(stroke
				(width 0.1524)
				(type default)
			)
			(layer "F.SilkS")
		)
		(fp_line
			(start -3.750056 5.500116)
			(end -3.750056 -5.500116)
			(stroke
				(width 0.1524)
				(type default)
			)
			(layer "F.SilkS")
		)
		(fp_line
			(start -2.393442 5.500116)
			(end -3.750056 5.500116)
			(stroke
				(width 0.1524)
				(type default)
			)
			(layer "F.SilkS")
		)
		(fp_line
			(start 2.393442 5.500116)
			(end 3.750056 5.500116)
			(stroke
				(width 0.1524)
				(type default)
			)
			(layer "F.SilkS")
		)
		(fp_line
			(start 3.750056 -5.500116)
			(end 2.393442 -5.500116)
			(stroke
				(width 0.1524)
				(type default)
			)
			(layer "F.SilkS")
		)
		(fp_line
			(start 3.750056 0.786892)
			(end 3.750056 -5.500116)
			(stroke
				(width 0.1524)
				(type default)
			)
			(layer "F.SilkS")
		)
		(fp_line
			(start 3.750056 5.500116)
			(end 3.750056 2.056892)
			(stroke
				(width 0.1524)
				(type default)
			)
			(layer "F.SilkS")
		)
		(fp_poly
			(pts
				(xy -3.060192 -6.962394) (xy -2.701036 -5.884672) (xy -3.778504 -6.244082)
			)
			(stroke
				(width 0)
				(type default)
			)
			(fill yes)
			(layer "F.SilkS")
		)
		(fp_line
			(start -3.750056 -5.500116)
			(end -3.750056 5.500116)
			(stroke
				(width 0.1)
				(type default)
			)
			(layer "F.Fab")
		)
		(fp_line
			(start -3.750056 5.500116)
			(end 3.750056 5.500116)
			(stroke
				(width 0.1)
				(type default)
			)
			(layer "F.Fab")
		)
		(fp_line
			(start 3.750056 -5.500116)
			(end -3.750056 -5.500116)
			(stroke
				(width 0.1)
				(type default)
			)
			(layer "F.Fab")
		)
		(fp_line
			(start 3.750056 5.500116)
			(end 3.750056 -5.500116)
			(stroke
				(width 0.1)
				(type default)
			)
			(layer "F.Fab")
		)
		(fp_poly
			(pts
				(xy -4.9276 -4.757928) (xy -4.9276 -3.741928) (xy -3.9116 -4.249928)
			)
			(stroke
				(width 0)
				(type default)
			)
			(fill yes)
			(layer "F.Fab")
		)
		(pad "1" smd rect
			(at 0 -4.249928 270)
			(size 2.413 4.5212)
			(layers "F.Cu" "F.Mask" "F.Paste")
			(net "SW_PVCCIN_CPU0_SW7")
		)
		(pad "2" smd rect
			(at 0 -1.175004 270)
			(size 1.3716 4.5212)
			(layers "F.Cu" "F.Mask" "F.Paste")
			(net "IND_P0_CPL7")
		)
		(pad "3" smd rect
			(at 0 1.175004 270)
			(size 1.3716 4.5212)
			(layers "F.Cu" "F.Mask" "F.Paste")
			(net "IND_P0_CPL6")
		)
		(pad "4" smd rect
			(at 0 4.249928 270)
			(size 2.413 4.5212)
			(layers "F.Cu" "F.Mask" "F.Paste")
			(net "PVCCIN_CPU0")
		)
	)
)
